FILE_TYPE = CONNECTIVITY;
{Allegro Design Entry HDL 17.4-2019 S026 (4007227) 1/17/2022}
"PAGE_NUMBER" = 451;
0"NC";
1"GND\g";
2"GND\g";
3"GND\g";
4"P1V8_CPU1_RT_1D\g";
5"GND\g";
6"GND\g";
7"P1V8_CPU1_RT_1D\g";
8"GND\g";
9"P1V8_CPU1_RT_1D\g";
10"GND\g";
11"GND\g";
12"GND\g";
13"P1V8_CPU1_RT_1D\g";
14"GND\g";
15"GND\g";
16"SMB_RT_CPU1_P2_ROM_MUX_1D_SCL";
17"SMB_RT_CPU1_P2_ROM_MUX_1D_R_SCL";
18"SMB_RT_CPU1_P2_ROM_MUX_1D_SDA";
19"SMB_RT_CPU1_P2_ROM_MUX_1D_R_SDA";
20"RT_CPU1_P2_SCAN_MODE";
21"JTAG_TDI_RT_CPU1_P2";
22"JTAG_TMS_RT_CPU1_P2";
23"JTAG_TDO_RT_CPU1_P2";
24"JTAG_TCK_RT_CPU1_P2";
25"P1V8_CPU1_RT_1D\g";
26"GND\g";
27"JTAG_TCK_RT_CPU1_P2";
28"JTAG_TDI_RT_CPU1_P2";
29"JTAG_TMS_RT_CPU1_P2";
30"JTAG_TDO_RT_CPU1_P2";
31"JTAG_TEST_MODE_RT_CPU1_P2";
32"GND\g";
33"P1V8_CPU1_RT_1D\g";
34"P1V8_CPU1_RT_1D\g";
35"RST_RT_CPU1_P2_RESET_N";
36"RST_RT_CPU1_P2_PERST_R_N";
37"RT_CPU1_P2_SCAN_MODE";
38"RST_RT_CPU1_P2_RESET_R_N";
39"RXDET_BYP_RT_CPU1_P2";
40"MODE_RT_CPU1_P2";
41"RXDET_BYP_RT_CPU1_P2";
42"CLKREQ_RT_CPU1_P2_N";
43"RST_RT_CPU1_P2_PERST_N";
44"JTAG_TRST_RT_CPU1_P2_N";
45"SMB_RT_CPU1_P2_R_SCL";
46"SMB_RT_CPU1_P2_R2_SCL";
47"CLK_100M_RETIMER_CPU1_P2_DP";
48"CLK_100M_RETIMER_CPU1_P2_R_DP";
49"CLK_100M_RETIMER_CPU1_P2_DN";
50"SMB_RT_CPU1_P2_R2_SDA";
51"RST_RT_CPU1_P2_PERST_R_N";
52"RST_RT_CPU1_P2_RESET_R_N";
53"GPIO3_RT_CPU1_P2";
54"RT_CPU1_P2_ADDR2";
55"RT_CPU1_P2_ADDR1";
56"RT_CPU1_P2_ADDR3";
57"MODE_RT_CPU1_P2";
58"TEST1_RT_CPU1_P2";
59"TEST2_RT_CPU1_P2";
60"JTAG_TEST_MODE_RT_CPU1_P2";
61"TEST0_RT_CPU1_P2";
62"GPIO2_RT_CPU1_P2";
63"GPIO3_RT_CPU1_P2";
64"GPIO2_RT_CPU1_P2";
65"SMB_RT_CPU1_P2_R_SDA";
66"RT_CPU1_P2_ADDR2";
67"RT_CPU1_P2_ADDR3";
68"RT_CPU1_P2_ADDR1";
69"TEST0_RT_CPU1_P2";
70"TEST1_RT_CPU1_P2";
71"TEST2_RT_CPU1_P2";
72"CLK_100M_RETIMER_CPU1_P2_R_DN";
%"Q_RES"
"1","(-2675,3225)","0","pure_quanta","I102";
;
LOCATION"R1416"
$SEC"1"
CDS_SEC"1"
VALUE"1K"
MATERIAL"CHIP"
PACK_TYPE"0201LF"
TOLERANCE"1%"
WATTAGE"1/20W"
CDS_LIB"pure_quanta"
PART_NUMBER"CS21001FE07";
"B"
$PN"2"3;
"A"
$PN"1"44;
%"UNIVERSAL_GND"
"1","(-1925,2275)","1","pure_quanta_power","I107";
;
CDS_LIB"pure_quanta_power"
HDL_POWER"GND";
"A"1;
%"GND"
"1","(-1500,2900)","0","pure_quanta_power","I108";
;
CDS_LIB"pure_quanta_power"
SIZE"1B"
BOM_COST"MEM"
HDL_POWER"GND";
"A<SIZE-1..0>\NAC"2;
%"UNIVERSAL_GND"
"1","(-1925,3225)","1","pure_quanta_power","I109";
;
CDS_LIB"pure_quanta_power"
HDL_POWER"GND";
"A"3;
%"Q_RES"
"2","(-1500,3300)","0","pure_quanta","I113";
;
LOCATION"R1427"
$SEC"1"
CDS_SEC"1"
MATERIAL"CHIP"
TOLERANCE"1%"
VALUE"10K"
WATTAGE"1/20W"
PACK_TYPE"0201LF"
CDS_LIB"pure_quanta"
PART_NUMBER"CS31001FE17";
"A"
$PN"1"41;
"B"
$PN"2"2;
%"Q_RES"
"2","(-1500,3825)","0","pure_quanta","I114";
;
LOCATION"R1426"
$SEC"1"
CDS_SEC"1"
VALUE"1K"
MATERIAL"EMPTY"
PACK_TYPE"0201LF"
WATTAGE"1/20W"
TOLERANCE"1%"
CDS_LIB"pure_quanta"
PART_NUMBER"CS21001FE07";
"A"
$PN"1"4;
"B"
$PN"2"41;
%"P1V0"
"1","(-1500,4225)","0","pure_quanta_power","I115";
;
HDL_POWER"P1V8_CPU1_RT_1D"
CDS_LIB"pure_quanta_power";
"A"4;
%"Q_RES"
"2","(-8950,3425)","0","pure_quanta","I119";
;
LOCATION"R869"
$SEC"1"
CDS_SEC"1"
MATERIAL"CHIP"
WATTAGE"1/20W"
VALUE"200"
TOLERANCE"1%"
PACK_TYPE"0201LF"
CDS_LIB"pure_quanta"
PART_NUMBER"CS12001FE12";
"A"
$PN"1"20;
"B"
$PN"2"6;
%"Q_RES"
"2","(-1425,1350)","0","pure_quanta","I132";
;
LOCATION"R1488"
$SEC"1"
CDS_SEC"1"
WATTAGE"1/20W"
VALUE"4.7K"
PACK_TYPE"0201LF"
TOLERANCE"5%"
MATERIAL"EMPTY"
CDS_LIB"pure_quanta"
PART_NUMBER"CS24701JE04";
"A"
$PN"1"25;
"B"
$PN"2"21;
%"GND"
"1","(-600,425)","0","pure_quanta_power","I134";
;
SIZE"1B"
BOM_COST"MEM"
CDS_LIB"pure_quanta_power"
HDL_POWER"GND";
"A<SIZE-1..0>\NAC"5;
%"Q_RES"
"2","(-600,725)","0","pure_quanta","I136";
;
LOCATION"R1417"
$SEC"1"
CDS_SEC"1"
MATERIAL"CHIP"
PACK_TYPE"0201LF"
WATTAGE"1/20W"
TOLERANCE"5%"
VALUE"4.7K"
CDS_LIB"pure_quanta"
PART_NUMBER"CS24701JE04";
"A"
$PN"1"24;
"B"
$PN"2"5;
%"Q_RES"
"2","(-600,1375)","0","pure_quanta","I137";
;
LOCATION"R1499"
$SEC"1"
CDS_SEC"1"
MATERIAL"EMPTY"
PACK_TYPE"0201LF"
WATTAGE"1/20W"
TOLERANCE"5%"
VALUE"4.7K"
CDS_LIB"pure_quanta"
PART_NUMBER"CS24701JE04";
"A"
$PN"1"25;
"B"
$PN"2"24;
%"P1V0"
"1","(-600,1675)","0","pure_quanta_power","I138";
;
HDL_POWER"P1V8_CPU1_RT_1D"
CDS_LIB"pure_quanta_power";
"A"25;
%"Q_RES"
"2","(-875,1350)","0","pure_quanta","I139";
;
LOCATION"R1490"
$SEC"1"
CDS_SEC"1"
MATERIAL"EMPTY"
PACK_TYPE"0201LF"
VALUE"1K"
TOLERANCE"1%"
WATTAGE"1/20W"
CDS_LIB"pure_quanta"
PART_NUMBER"CS21001FE07";
"A"
$PN"1"25;
"B"
$PN"2"23;
%"Q_RES"
"2","(-1150,1350)","0","pure_quanta","I140";
;
LOCATION"R1489"
$SEC"1"
CDS_SEC"1"
MATERIAL"EMPTY"
PACK_TYPE"0201LF"
TOLERANCE"5%"
WATTAGE"1/20W"
VALUE"4.7K"
CDS_LIB"pure_quanta"
PART_NUMBER"CS24701JE04";
"A"
$PN"1"25;
"B"
$PN"2"22;
%"UNIVERSAL_GND"
"1","(-8950,3150)","0","pure_quanta_power","I15";
;
CDS_LIB"pure_quanta_power"
HDL_POWER"GND";
"A"6;
%"Q_RES"
"2","(-8950,4100)","0","pure_quanta","I17";
;
LOCATION"R868"
$SEC"1"
CDS_SEC"1"
PACK_TYPE"0201LF"
TOLERANCE"5%"
VALUE"4.7K"
WATTAGE"1/20W"
MATERIAL"EMPTY"
CDS_LIB"pure_quanta"
PART_NUMBER"CS24701JE04";
"A"
$PN"1"7;
"B"
$PN"2"20;
%"P1V0"
"1","(-8950,4425)","0","pure_quanta_power","I18";
;
HDL_POWER"P1V8_CPU1_RT_1D"
CDS_LIB"pure_quanta_power";
"A"7;
%"Q_RES"
"2","(-8925,5025)","0","pure_quanta","I19";
;
LOCATION"R875"
$SEC"1"
CDS_SEC"1"
PACK_TYPE"0201LF"
MATERIAL"CHIP"
WATTAGE"1/20W"
TOLERANCE"1%"
VALUE"10K"
CDS_LIB"pure_quanta"
PART_NUMBER"CS31001FE17";
"A"
$PN"1"64;
"B"
$PN"2"26;
%"Q_RES"
"2","(-8625,5025)","0","pure_quanta","I20";
;
LOCATION"R876"
$SEC"1"
CDS_SEC"1"
PACK_TYPE"0201LF"
MATERIAL"CHIP"
WATTAGE"1/20W"
TOLERANCE"1%"
VALUE"10K"
CDS_LIB"pure_quanta"
PART_NUMBER"CS31001FE17";
"A"
$PN"1"63;
"B"
$PN"2"26;
%"Q_RES"
"2","(-8925,5975)","0","pure_quanta","I21";
;
LOCATION"R874"
$SEC"1"
CDS_SEC"1"
WATTAGE"1/20W"
VALUE"4.7K"
MATERIAL"EMPTY"
PACK_TYPE"0201LF"
TOLERANCE"5%"
CDS_LIB"pure_quanta"
PART_NUMBER"CS24701JE04";
"A"
$PN"1"34;
"B"
$PN"2"64;
%"P1V0"
"1","(-8925,6375)","0","pure_quanta_power","I22";
;
HDL_POWER"P1V8_CPU1_RT_1D"
CDS_LIB"pure_quanta_power";
"A"34;
%"Q_RES"
"1","(-6575,1025)","0","pure_quanta","I27";
;
LOCATION"R620"
SEC"1"
PACK_TYPE"0201LF"
MATERIAL"CHIP"
CDS_LIB"pure_quanta"
TOLERANCE"5%"
VALUE"0"
WATTAGE"1/20W"
SEC_TYPE"0201LF"
PART_NUMBER"CS00001JE10";
"B"
$PN"2"49;
"A"
$PN"1"72;
%"Q_RES"
"1","(-6575,1175)","0","pure_quanta","I28";
;
LOCATION"R619"
SEC"1"
MATERIAL"CHIP"
VALUE"0"
TOLERANCE"5%"
WATTAGE"1/20W"
PACK_TYPE"0201LF"
CDS_LIB"pure_quanta"
SEC_TYPE"0201LF"
PART_NUMBER"CS00001JE10";
"B"
$PN"2"47;
"A"
$PN"1"48;
%"Q_RES"
"1","(-6300,1525)","0","pure_quanta","I29";
;
LOCATION"R692"
$SEC"1"
CDS_SEC"1"
CDS_LIB"pure_quanta"
MATERIAL"CHIP"
WATTAGE"1/20W"
PACK_TYPE"0201LF"
VALUE"49.9"
TOLERANCE"1%"
PART_NUMBER"CS04991FE06";
"B"
$PN"2"19;
"A"
$PN"1"18;
%"Q_RES"
"1","(-6300,1625)","0","pure_quanta","I30";
;
LOCATION"R691"
$SEC"1"
CDS_SEC"1"
MATERIAL"CHIP"
WATTAGE"1/20W"
PACK_TYPE"0201LF"
VALUE"49.9"
TOLERANCE"1%"
CDS_LIB"pure_quanta"
PART_NUMBER"CS04991FE06";
"B"
$PN"2"17;
"A"
$PN"1"16;
%"Q_RES"
"1","(-6325,2875)","0","pure_quanta","I34";
;
LOCATION"R872"
$SEC"1"
CDS_SEC"1"
TOLERANCE"5%"
WATTAGE"1/20W"
MATERIAL"CHIP"
VALUE"0"
PACK_TYPE"0201LF"
CDS_LIB"pure_quanta"
PART_NUMBER"CS00001JE10";
"B"
$PN"2"46;
"A"
$PN"1"45;
%"Q_RES"
"1","(-6325,2775)","0","pure_quanta","I35";
;
LOCATION"R873"
$SEC"1"
CDS_SEC"1"
WATTAGE"1/20W"
VALUE"0"
TOLERANCE"5%"
MATERIAL"CHIP"
PACK_TYPE"0201LF"
CDS_LIB"pure_quanta"
PART_NUMBER"CS00001JE10";
"B"
$PN"2"50;
"A"
$PN"1"65;
%"Q_RES"
"2","(-6125,700)","0","pure_quanta","I36";
;
LOCATION"R640"
$SEC"1"
CDS_SEC"1"
PACK_TYPE"0201LF"
TOLERANCE"1%"
MATERIAL"EMPTY"
WATTAGE"1/20W"
VALUE"51.1"
CDS_LIB"pure_quanta"
PART_NUMBER"CS05111FE00";
"A"
$PN"1"47;
"B"
$PN"2"14;
%"Q_RES"
"2","(-8300,5025)","0","pure_quanta","I42";
;
LOCATION"R879"
$SEC"1"
CDS_SEC"1"
MATERIAL"CHIP"
PACK_TYPE"0201LF"
WATTAGE"1/20W"
TOLERANCE"5%"
VALUE"4.7K"
CDS_LIB"pure_quanta"
PART_NUMBER"CS24701JE04";
"A"
$PN"1"61;
"B"
$PN"2"26;
%"Q_RES"
"2","(-8000,5000)","0","pure_quanta","I43";
;
LOCATION"R881"
$SEC"1"
CDS_SEC"1"
WATTAGE"1/20W"
MATERIAL"CHIP"
PACK_TYPE"0201LF"
TOLERANCE"5%"
VALUE"4.7K"
CDS_LIB"pure_quanta"
PART_NUMBER"CS24701JE04";
"A"
$PN"1"58;
"B"
$PN"2"26;
%"UNIVERSAL_GND"
"1","(-7400,4525)","0","pure_quanta_power","I44";
;
CDS_LIB"pure_quanta_power"
HDL_POWER"GND";
"A"26;
%"Q_RES"
"2","(-7700,5000)","0","pure_quanta","I45";
;
LOCATION"R883"
$SEC"1"
CDS_SEC"1"
WATTAGE"1/20W"
TOLERANCE"5%"
VALUE"4.7K"
PACK_TYPE"0201LF"
MATERIAL"CHIP"
CDS_LIB"pure_quanta"
PART_NUMBER"CS24701JE04";
"A"
$PN"1"59;
"B"
$PN"2"26;
%"Q_RES"
"2","(-7400,4975)","0","pure_quanta","I46";
;
LOCATION"R884"
$SEC"1"
CDS_SEC"1"
PACK_TYPE"0201LF"
TOLERANCE"5%"
VALUE"4.7K"
MATERIAL"CHIP"
WATTAGE"1/20W"
CDS_LIB"pure_quanta"
PART_NUMBER"CS24701JE04";
"A"
$PN"1"60;
"B"
$PN"2"26;
%"Q_RES"
"2","(-8300,5975)","0","pure_quanta","I47";
;
LOCATION"R878"
$SEC"1"
CDS_SEC"1"
VALUE"4.7K"
WATTAGE"1/20W"
MATERIAL"EMPTY"
PACK_TYPE"0201LF"
TOLERANCE"5%"
CDS_LIB"pure_quanta"
PART_NUMBER"CS24701JE04";
"A"
$PN"1"34;
"B"
$PN"2"61;
%"Q_RES"
"2","(-8000,5925)","0","pure_quanta","I48";
;
LOCATION"R880"
$SEC"1"
CDS_SEC"1"
MATERIAL"EMPTY"
PACK_TYPE"0201LF"
VALUE"4.7K"
TOLERANCE"5%"
WATTAGE"1/20W"
CDS_LIB"pure_quanta"
PART_NUMBER"CS24701JE04";
"A"
$PN"1"34;
"B"
$PN"2"58;
%"Q_RES"
"2","(-7700,5950)","0","pure_quanta","I49";
;
LOCATION"R882"
$SEC"1"
CDS_SEC"1"
TOLERANCE"5%"
PACK_TYPE"0201LF"
MATERIAL"EMPTY"
WATTAGE"1/20W"
VALUE"4.7K"
CDS_LIB"pure_quanta"
PART_NUMBER"CS24701JE04";
"A"
$PN"1"34;
"B"
$PN"2"59;
%"Q_RES"
"2","(-7400,5975)","0","pure_quanta","I50";
;
LOCATION"R871"
$SEC"1"
CDS_SEC"1"
PACK_TYPE"0201LF"
VALUE"4.7K"
TOLERANCE"5%"
MATERIAL"EMPTY"
WATTAGE"1/20W"
CDS_LIB"pure_quanta"
PART_NUMBER"CS24701JE04";
"A"
$PN"1"34;
"B"
$PN"2"60;
%"UNIVERSAL_GND"
"1","(-5000,5175)","0","pure_quanta_power","I57";
;
CDS_LIB"pure_quanta_power"
HDL_POWER"GND";
"A"8;
%"Q_RES"
"2","(-5000,5525)","0","pure_quanta","I58";
;
LOCATION"R886"
$SEC"1"
CDS_SEC"1"
VALUE"4.7K"
WATTAGE"1/20W"
PACK_TYPE"0201LF"
TOLERANCE"5%"
MATERIAL"EMPTY"
CDS_LIB"pure_quanta"
PART_NUMBER"CS24701JE04";
"A"
$PN"1"57;
"B"
$PN"2"8;
%"Q_RES"
"2","(-5000,6050)","0","pure_quanta","I59";
;
LOCATION"R885"
$SEC"1"
CDS_SEC"1"
PACK_TYPE"0201LF"
MATERIAL"CHIP"
WATTAGE"1/20W"
TOLERANCE"5%"
VALUE"4.7K"
CDS_LIB"pure_quanta"
PART_NUMBER"CS24701JE04";
"A"
$PN"1"9;
"B"
$PN"2"57;
%"P1V0"
"1","(-5000,6375)","0","pure_quanta_power","I60";
;
HDL_POWER"P1V8_CPU1_RT_1D"
CDS_LIB"pure_quanta_power";
"A"9;
%"UNIVERSAL_GND"
"1","(-3325,1675)","1","pure_quanta_power","I61";
;
CDS_LIB"pure_quanta_power"
HDL_POWER"GND";
"A"10;
%"Q_RES"
"1","(-2550,2075)","0","pure_quanta","I62";
;
LOCATION"R860"
$SEC"1"
CDS_SEC"1"
VALUE"0"
PACK_TYPE"0201LF"
WATTAGE"1/20W"
TOLERANCE"5%"
MATERIAL"CHIP"
CDS_LIB"pure_quanta"
PART_NUMBER"CS00001JE10";
"B"
$PN"2"38;
"A"
$PN"1"35;
%"Q_RES"
"1","(-2550,2175)","0","pure_quanta","I63";
;
LOCATION"R854"
SEC"1"
PACK_TYPE"0201LF"
VALUE"0"
CDS_LIB"pure_quanta"
SEC_TYPE"0201LF"
MATERIAL"CHIP"
TOLERANCE"5%"
WATTAGE"1/20W"
PART_NUMBER"CS00001JE10";
"B"
$PN"2"36;
"A"
$PN"1"43;
%"Q_RES"
"2","(-3600,5300)","0","pure_quanta","I71";
;
LOCATION"R863"
$SEC"1"
CDS_SEC"1"
MATERIAL"EMPTY"
VALUE"1K"
TOLERANCE"1%"
WATTAGE"1/20W"
PACK_TYPE"0201LF"
CDS_LIB"pure_quanta"
PART_NUMBER"CS21001FE07";
"A"
$PN"1"56;
"B"
$PN"2"32;
%"Q_RES"
"2","(-3300,5300)","0","pure_quanta","I72";
;
LOCATION"R865"
$SEC"1"
CDS_SEC"1"
PACK_TYPE"0201LF"
MATERIAL"CHIP"
WATTAGE"1/20W"
TOLERANCE"1%"
VALUE"20K"
CDS_LIB"pure_quanta"
PART_NUMBER"CS32001FE00";
"A"
$PN"1"54;
"B"
$PN"2"32;
%"Q_RES"
"2","(-3600,6075)","0","pure_quanta","I74";
;
LOCATION"R861"
$SEC"1"
CDS_SEC"1"
VALUE"1K"
TOLERANCE"1%"
WATTAGE"1/20W"
PACK_TYPE"0201LF"
MATERIAL"CHIP"
CDS_LIB"pure_quanta"
PART_NUMBER"CS21001FE07";
"A"
$PN"1"33;
"B"
$PN"2"56;
%"Q_RES"
"2","(-3300,6075)","0","pure_quanta","I75";
;
LOCATION"R864"
$SEC"1"
CDS_SEC"1"
PACK_TYPE"0201LF"
TOLERANCE"1%"
VALUE"1K"
WATTAGE"1/20W"
MATERIAL"EMPTY"
CDS_LIB"pure_quanta"
PART_NUMBER"CS21001FE07";
"A"
$PN"1"33;
"B"
$PN"2"54;
%"Q_RES"
"2","(-2950,5300)","0","pure_quanta","I76";
;
LOCATION"R892"
$SEC"1"
CDS_SEC"1"
MATERIAL"CHIP"
TOLERANCE"1%"
WATTAGE"1/20W"
PACK_TYPE"0201LF"
VALUE"1K"
CDS_LIB"pure_quanta"
PART_NUMBER"CS21001FE07";
"A"
$PN"1"55;
"B"
$PN"2"32;
%"Q_RES"
"2","(-2950,6050)","0","pure_quanta","I77";
;
LOCATION"R887"
$SEC"1"
CDS_SEC"1"
MATERIAL"EMPTY"
TOLERANCE"1%"
VALUE"1K"
WATTAGE"1/20W"
PACK_TYPE"0201LF"
CDS_LIB"pure_quanta"
PART_NUMBER"CS21001FE07";
"A"
$PN"1"33;
"B"
$PN"2"55;
%"P1V0"
"1","(-3600,6500)","0","pure_quanta_power","I78";
;
HDL_POWER"P1V8_CPU1_RT_1D"
CDS_LIB"pure_quanta_power";
"A"33;
%"GND"
"1","(-1450,4825)","0","pure_quanta_power","I79";
;
BOM_COST"MEM"
SIZE"1B"
CDS_LIB"pure_quanta_power"
HDL_POWER"GND";
"A<SIZE-1..0>\NAC"11;
%"Q_RES"
"2","(-1450,5200)","2","pure_quanta","I80";
;
LOCATION"R867"
$SEC"1"
CDS_SEC"1"
TOLERANCE"1%"
WATTAGE"1/20W"
VALUE"10K"
PACK_TYPE"0201LF"
MATERIAL"CHIP"
CDS_LIB"pure_quanta"
PART_NUMBER"CS31001FE17";
"A"
$PN"1"52;
"B"
$PN"2"11;
%"GND"
"1","(-1275,4850)","0","pure_quanta_power","I81";
;
CDS_LIB"pure_quanta_power"
BOM_COST"MEM"
SIZE"1B"
HDL_POWER"GND";
"A<SIZE-1..0>\NAC"12;
%"Q_RES"
"2","(-1275,5200)","0","pure_quanta","I82";
;
LOCATION"R866"
$SEC"1"
CDS_SEC"1"
PACK_TYPE"0201LF"
MATERIAL"CHIP"
TOLERANCE"1%"
WATTAGE"1/20W"
VALUE"10K"
CDS_LIB"pure_quanta"
PART_NUMBER"CS31001FE17";
"A"
$PN"1"51;
"B"
$PN"2"12;
%"Q_RES"
"2","(-1450,6025)","2","pure_quanta","I86";
;
LOCATION"R870"
$SEC"1"
CDS_SEC"1"
TOLERANCE"5%"
WATTAGE"1/20W"
VALUE"4.7K"
MATERIAL"EMPTY"
PACK_TYPE"0201LF"
CDS_LIB"pure_quanta"
PART_NUMBER"CS24701JE04";
"A"
$PN"1"13;
"B"
$PN"2"52;
%"P1V0"
"1","(-1450,6275)","0","pure_quanta_power","I87";
;
HDL_POWER"P1V8_CPU1_RT_1D"
CDS_LIB"pure_quanta_power";
"A"13;
%"UNIVERSAL_GND"
"1","(-6125,375)","0","pure_quanta_power","I90";
;
CDS_LIB"pure_quanta_power"
HDL_POWER"GND";
"A"14;
%"UNIVERSAL_GND"
"1","(-6275,375)","0","pure_quanta_power","I91";
;
CDS_LIB"pure_quanta_power"
HDL_POWER"GND";
"A"15;
%"Q_RES"
"2","(-6275,700)","2","pure_quanta","I92";
;
LOCATION"R637"
$SEC"1"
CDS_SEC"1"
WATTAGE"1/20W"
VALUE"51.1"
PACK_TYPE"0201LF"
TOLERANCE"1%"
MATERIAL"EMPTY"
CDS_LIB"pure_quanta"
PART_NUMBER"CS05111FE00";
"A"
$PN"1"49;
"B"
$PN"2"15;
%"UNIVERSAL_GND"
"1","(-3600,4875)","0","pure_quanta_power","I96";
;
CDS_LIB"pure_quanta_power"
HDL_POWER"GND";
"A"32;
%"PT5161LRS"
"3","(-4350,2325)","0","pure_quanta","I97";
;
LOCATION"U6016"
$SEC"3"
CDS_SEC"3"
PART_TYPE"SMLF"
VALUE"PT5161LRS"
MATERIAL"IC"
NEEDS_NO_SIZE"TRUE"
CDS_LMAN_SYM_OUTLINE"-500,1450,450,-1400"
CDS_LIB"pure_quanta"
PART_NUMBER"AJ051610U03";
"EE_DAT"
$PN"FJ3"19;
"EE_CLK"
$PN"FF5"17;
"CLKREQ_N \B"
$PN"G35"42;
"TEST2"
$PN"FF30"71;
"TEST1"
$PN"FF27"70;
"TEST0"
$PN"FF24"69;
"T_SENSE"
$PN"E30"10;
"SMBDAT"
$PN"B28"50;
"SMBCLK"
$PN"B31"46;
"SMB_ADDR3"
$PN"B25"67;
"SMB_ADDR2"
$PN"B23"66;
"SMB_ADDR1"
$PN"F34"68;
"SCAN_MODE"
$PN"FF33"37;
"RXDET_BYP"
$PN"E11"39;
"RESET_N \B"
$PN"FF11"35;
"REFCLKP"
$PN"FJ16"47;
"REFCLKN"
$PN"FF18"49;
"REFCLK_OUTP"
$PN"B16"0;
"REFCLK_OUTN"
$PN"E18"0;
"PERST_N \B"
$PN"F2"43;
"MODE"
$PN"FJ9"40;
"JTAG_TRST_N \B"
$PN"E8"44;
"JTAG_TMS"
$PN"B12"29;
"JTAG_TEST_MODE"
$PN"FF8"31;
"JTAG_TDO"
$PN"B9"30;
"JTAG_TDI"
$PN"B6"28;
"JTAG_TCK"
$PN"B3"27;
"INT_N \B"
$PN"FJ31"0;
"GPIO3"
$PN"FJ28"53;
"GPIO2"
$PN"FJ25"62;
"GPIO1"
$PN"FJ23"0;
"GPIO0"
$PN"FJ6"0;
%"Q_RES"
"1","(-2650,2275)","0","pure_quanta","I98";
;
LOCATION"R1421"
$SEC"1"
CDS_SEC"1"
VALUE"4.7K"
PACK_TYPE"0201LF"
MATERIAL"CHIP"
CDS_LIB"pure_quanta"
TOLERANCE"5%"
WATTAGE"1/20W"
PART_NUMBER"CS24701JE04";
"B"
$PN"2"1;
"A"
$PN"1"42;
END.
